# T6G (Grand Teton) — schematic netlist excerpt (pin names and nets, part order shuffled) for the footprints in the layout excerpt that follows; sources: Cadence DE-HDL packaged netlist, KiCad conversion of 04192023_DAF0TMB3IC0_F0TG_MB_C_brd_V02_OCP.brd

R192  Q_RES  0 5% EMPTY  pkg 0402LF  page 55 : A = FM_CPU1_SLP_S3_N ; B = CPU1_SLP_S3_N
C6025  Q_CAP  0.1UF 25V 10% X7R  pkg 0402  page 180 : A = USB3_CPU0_BMC_HUB2_TX_DP ; B = USB3_CPU0_BMC_TX_BUF_C_DP
PC120  Q_CAP  22UF 16V 20% X6S  pkg C0805  page 192 : A = SW_P12V_AUX_PVDD_33_S5_FLT ; B = GND

(kicad_pcb
	(version 20260206)
	(generator "pcbnew")
	(generator_version "10.0")
	(general
		(thickness 1.6)
		(legacy_teardrops no)
	)
	(paper "A4")
	(title_block
		(title "04192023_DAF0TMB3IC0_F0TG_MB_C_brd_V02_OCP.brd")
		(comment 1 "Grand Teton / footprints 832-834 of 8354")
	)
	(layers
		(0 "F.Cu" signal "TOP")
		(4 "In1.Cu" signal "GND")
		(6 "In2.Cu" signal "IN1")
		(8 "In3.Cu" signal "GND1")
		(10 "In4.Cu" signal "IN2")
		(12 "In5.Cu" signal "GND2")
		(14 "In6.Cu" signal "IN3")
		(16 "In7.Cu" signal "GND3")
		(18 "In8.Cu" signal "VCC")
		(20 "In9.Cu" signal "VCC1")
		(22 "In10.Cu" signal "GND4")
		(24 "In11.Cu" signal "IN4")
		(26 "In12.Cu" signal "GND5")
		(28 "In13.Cu" signal "IN5")
		(30 "In14.Cu" signal "GND6")
		(32 "In15.Cu" signal "IN6")
		(34 "In16.Cu" signal "GND7")
		(2 "B.Cu" signal "BOTTOM")
		(9 "F.Adhes" user "F.Adhesive")
		(11 "B.Adhes" user "B.Adhesive")
		(13 "F.Paste" user "Package Geometry/Pastemask Top")
		(15 "B.Paste" user "Package Geometry/Pastemask Bottom")
		(5 "F.SilkS" user "Ref Des/Silkscreen Top")
		(7 "B.SilkS" user "Ref Des/Silkscreen Bottom")
		(1 "F.Mask" user "Board Geometry/Soldermask Top")
		(3 "B.Mask" user "Board Geometry/Soldermask Bottom")
		(17 "Dwgs.User" user "User.Drawings")
		(19 "Cmts.User" user "User.Comments")
		(21 "Eco1.User" user "User.Eco1")
		(23 "Eco2.User" user "User.Eco2")
		(25 "Edge.Cuts" user "Board Geometry/Outline")
		(27 "Margin" user)
		(31 "F.CrtYd" user "Package Geometry/Place Bound Top")
		(29 "B.CrtYd" user "Package Geometry/Place Bound Bottom")
		(35 "F.Fab" user "Ref Des/Assembly Top")
		(33 "B.Fab" user "Ref Des/Assembly Bottom")
	)
	(footprint ""
		(layer "F.Cu")
		(at 122.55627 -36.675568)
		(property "Reference" "C6025"
			(at 0 0 0)
			(layer "F.SilkS")
			(hide yes)
			(effects
				(font
					(size 1.27 1.27)
				)
			)
		)
		(property "Value" ""
			(at 0 0 0)
			(layer "F.Fab")
			(effects
				(font
					(size 1.27 1.27)
				)
			)
		)
		(duplicate_pad_numbers_are_jumpers no)
		(fp_line
			(start -0.7874 -0.4064)
			(end 0.7874 -0.4064)
			(stroke
				(width 0.1524)
				(type default)
			)
			(layer "F.SilkS")
		)
		(fp_line
			(start -0.7874 0.4064)
			(end -0.7874 -0.4064)
			(stroke
				(width 0.1524)
				(type default)
			)
			(layer "F.SilkS")
		)
		(fp_line
			(start 0.7874 -0.4064)
			(end 0.7874 0.4064)
			(stroke
				(width 0.1524)
				(type default)
			)
			(layer "F.SilkS")
		)
		(fp_line
			(start 0.7874 0.4064)
			(end -0.7874 0.4064)
			(stroke
				(width 0.1524)
				(type default)
			)
			(layer "F.SilkS")
		)
		(fp_line
			(start -0.6858 -0.3048)
			(end -0.1016 -0.3048)
			(stroke
				(width 0.1)
				(type default)
			)
			(layer "F.Fab")
		)
		(fp_line
			(start -0.6858 0.3048)
			(end -0.6858 -0.3048)
			(stroke
				(width 0.1)
				(type default)
			)
			(layer "F.Fab")
		)
		(fp_line
			(start -0.1016 -0.3048)
			(end -0.1016 -0.2794)
			(stroke
				(width 0.1)
				(type default)
			)
			(layer "F.Fab")
		)
		(fp_line
			(start -0.1016 -0.2794)
			(end 0.1016 -0.2794)
			(stroke
				(width 0.1)
				(type default)
			)
			(layer "F.Fab")
		)
		(fp_line
			(start -0.1016 0.2794)
			(end -0.1016 0.3048)
			(stroke
				(width 0.1)
				(type default)
			)
			(layer "F.Fab")
		)
		(fp_line
			(start -0.1016 0.3048)
			(end -0.6858 0.3048)
			(stroke
				(width 0.1)
				(type default)
			)
			(layer "F.Fab")
		)
		(fp_line
			(start 0.1016 -0.3048)
			(end 0.6858 -0.3048)
			(stroke
				(width 0.1)
				(type default)
			)
			(layer "F.Fab")
		)
		(fp_line
			(start 0.1016 -0.2794)
			(end 0.1016 -0.3048)
			(stroke
				(width 0.1)
				(type default)
			)
			(layer "F.Fab")
		)
		(fp_line
			(start 0.1016 0.2794)
			(end -0.1016 0.2794)
			(stroke
				(width 0.1)
				(type default)
			)
			(layer "F.Fab")
		)
		(fp_line
			(start 0.1016 0.3048)
			(end 0.1016 0.2794)
			(stroke
				(width 0.1)
				(type default)
			)
			(layer "F.Fab")
		)
		(fp_line
			(start 0.6858 -0.3048)
			(end 0.6858 0.3048)
			(stroke
				(width 0.1)
				(type default)
			)
			(layer "F.Fab")
		)
		(fp_line
			(start 0.6858 0.3048)
			(end 0.1016 0.3048)
			(stroke
				(width 0.1)
				(type default)
			)
			(layer "F.Fab")
		)
		(pad "1" smd rect
			(at -0.40005 0 180)
			(size 0.4572 0.508)
			(layers "F.Cu" "F.Mask" "F.Paste")
			(net "USB3_CPU0_BMC_HUB2_TX_DP")
		)
		(pad "2" smd rect
			(at 0.40005 0 180)
			(size 0.4572 0.508)
			(layers "F.Cu" "F.Mask" "F.Paste")
			(net "USB3_CPU0_BMC_TX_BUF_C_DP")
		)
	)
	(footprint ""
		(layer "F.Cu")
		(at 199.941942 -344.270584 180)
		(property "Reference" "PC120"
			(at 0 0 180)
			(layer "F.SilkS")
			(hide yes)
			(effects
				(font
					(size 1.27 1.27)
				)
			)
		)
		(property "Value" ""
			(at 0 0 180)
			(layer "F.Fab")
			(effects
				(font
					(size 1.27 1.27)
				)
			)
		)
		(duplicate_pad_numbers_are_jumpers no)
		(fp_line
			(start 1.524 0.762)
			(end -1.524 0.762)
			(stroke
				(width 0.1524)
				(type default)
			)
			(layer "F.SilkS")
		)
		(fp_line
			(start 1.524 -0.762)
			(end 1.524 0.762)
			(stroke
				(width 0.1524)
				(type default)
			)
			(layer "F.SilkS")
		)
		(fp_line
			(start -1.524 0.762)
			(end -1.524 -0.762)
			(stroke
				(width 0.1524)
				(type default)
			)
			(layer "F.SilkS")
		)
		(fp_line
			(start -1.524 -0.762)
			(end 1.524 -0.762)
			(stroke
				(width 0.1524)
				(type default)
			)
			(layer "F.SilkS")
		)
		(fp_line
			(start 1.1049 0.724916)
			(end 1.1049 -0.724916)
			(stroke
				(width 0.1)
				(type default)
			)
			(layer "F.Fab")
		)
		(fp_line
			(start 1.1049 -0.724916)
			(end -1.1049 -0.724916)
			(stroke
				(width 0.1)
				(type default)
			)
			(layer "F.Fab")
		)
		(fp_line
			(start -1.1049 0.724916)
			(end 1.1049 0.724916)
			(stroke
				(width 0.1)
				(type default)
			)
			(layer "F.Fab")
		)
		(fp_line
			(start -1.1049 -0.724916)
			(end -1.1049 0.724916)
			(stroke
				(width 0.1)
				(type default)
			)
			(layer "F.Fab")
		)
		(pad "1" smd rect
			(at -0.889 0)
			(size 1.016 1.27)
			(layers "F.Cu" "F.Mask" "F.Paste")
			(net "SW_P12V_AUX_PVDD_33_S5_FLT")
		)
		(pad "2" smd rect
			(at 0.889 0)
			(size 1.016 1.27)
			(layers "F.Cu" "F.Mask" "F.Paste")
			(net "GND")
		)
	)
	(footprint ""
		(layer "F.Cu")
		(at 176.911 -129.377948 90)
		(property "Reference" "R192"
			(at 0 0 90)
			(layer "F.SilkS")
			(hide yes)
			(effects
				(font
					(size 1.27 1.27)
				)
			)
		)
		(property "Value" ""
			(at 0 0 90)
			(layer "F.Fab")
			(effects
				(font
					(size 1.27 1.27)
				)
			)
		)
		(duplicate_pad_numbers_are_jumpers no)
		(fp_line
			(start 0.7874 -0.4064)
			(end 0.7874 0.4064)
			(stroke
				(width 0.1524)
				(type default)
			)
			(layer "F.SilkS")
		)
		(fp_line
			(start -0.7874 -0.4064)
			(end 0.7874 -0.4064)
			(stroke
				(width 0.1524)
				(type default)
			)
			(layer "F.SilkS")
		)
		(fp_line
			(start 0.7874 0.4064)
			(end -0.7874 0.4064)
			(stroke
				(width 0.1524)
				(type default)
			)
			(layer "F.SilkS")
		)
		(fp_line
			(start -0.7874 0.4064)
			(end -0.7874 -0.4064)
			(stroke
				(width 0.1524)
				(type default)
			)
			(layer "F.SilkS")
		)
		(fp_line
			(start -0.12065 -0.305054)
			(end -0.12065 -0.2794)
			(stroke
				(width 0.1)
				(type default)
			)
			(layer "F.Fab")
		)
		(fp_line
			(start -0.67945 -0.305054)
			(end -0.12065 -0.305054)
			(stroke
				(width 0.1)
				(type default)
			)
			(layer "F.Fab")
		)
		(fp_line
			(start 0.67945 -0.3048)
			(end 0.67945 0.3048)
			(stroke
				(width 0.1)
				(type default)
			)
			(layer "F.Fab")
		)
		(fp_line
			(start 0.12065 -0.3048)
			(end 0.67945 -0.3048)
			(stroke
				(width 0.1)
				(type default)
			)
			(layer "F.Fab")
		)
		(fp_line
			(start 0.12065 -0.2794)
			(end 0.12065 -0.3048)
			(stroke
				(width 0.1)
				(type default)
			)
			(layer "F.Fab")
		)
		(fp_line
			(start -0.12065 -0.2794)
			(end 0.12065 -0.2794)
			(stroke
				(width 0.1)
				(type default)
			)
			(layer "F.Fab")
		)
		(fp_line
			(start 0.120396 0.2794)
			(end -0.12065 0.2794)
			(stroke
				(width 0.1)
				(type default)
			)
			(layer "F.Fab")
		)
		(fp_line
			(start -0.12065 0.2794)
			(end -0.12065 0.3048)
			(stroke
				(width 0.1)
				(type default)
			)
			(layer "F.Fab")
		)
		(fp_line
			(start 0.67945 0.3048)
			(end 0.120396 0.3048)
			(stroke
				(width 0.1)
				(type default)
			)
			(layer "F.Fab")
		)
		(fp_line
			(start 0.120396 0.3048)
			(end 0.120396 0.2794)
			(stroke
				(width 0.1)
				(type default)
			)
			(layer "F.Fab")
		)
		(fp_line
			(start -0.12065 0.3048)
			(end -0.67945 0.3048)
			(stroke
				(width 0.1)
				(type default)
			)
			(layer "F.Fab")
		)
		(fp_line
			(start -0.67945 0.3048)
			(end -0.67945 -0.305054)
			(stroke
				(width 0.1)
				(type default)
			)
			(layer "F.Fab")
		)
		(pad "1" smd circle
			(at -0.40005 0 90)
			(size 0 0)
			(layers "F.Cu" "F.Mask" "F.Paste")
			(net "FM_CPU1_SLP_S3_N")
		)
		(pad "2" smd circle
			(at 0.40005 0 90)
			(size 0 0)
			(layers "F.Cu" "F.Mask" "F.Paste")
			(net "CPU1_SLP_S3_N")
		)
	)
)
